(kicad_pcb
	(version 20260206)
	(generator "pcbnew")
	(generator_version "10.0")
	(general
		(thickness 1.6)
		(legacy_teardrops no)
	)
	(paper "A4")
	(title_block
		(title "fcb — Lightning_FCB_BRD.brd")
		(comment 1 "Lightning (Wiwynn / Facebook NVMe JBOF) / footprints 269-274 of 495")
	)
	(layers
		(0 "F.Cu" signal "TOP")
		(4 "In1.Cu" signal "L2GND")
		(6 "In2.Cu" signal "L3VCC")
		(2 "B.Cu" signal "BOTTOM")
		(9 "F.Adhes" user "F.Adhesive")
		(11 "B.Adhes" user "B.Adhesive")
		(13 "F.Paste" user "Package Geometry/Pastemask Top")
		(15 "B.Paste" user "Package Geometry/Pastemask Bottom")
		(5 "F.SilkS" user "Ref Des/Silkscreen Top")
		(7 "B.SilkS" user "Ref Des/Silkscreen Bottom")
		(1 "F.Mask" user "Board Geometry/Soldermask Top")
		(3 "B.Mask" user "Board Geometry/Soldermask Bottom")
		(17 "Dwgs.User" user "User.Drawings")
		(19 "Cmts.User" user "User.Comments")
		(21 "Eco1.User" user "User.Eco1")
		(23 "Eco2.User" user "User.Eco2")
		(25 "Edge.Cuts" user "Board Geometry/Outline")
		(27 "Margin" user)
		(31 "F.CrtYd" user "Package Geometry/Place Bound Top")
		(29 "B.CrtYd" user "Package Geometry/Place Bound Bottom")
		(35 "F.Fab" user "Ref Des/Assembly Top")
		(33 "B.Fab" user "Ref Des/Assembly Bottom")
	)
	(footprint ""
		(layer "F.Cu")
		(at 28.1686 -224.3074)
		(property "Reference" "R140"
			(at 0 0 0)
			(layer "F.SilkS")
			(hide yes)
			(effects
				(font
					(size 1.27 1.27)
				)
			)
		)
		(property "Value" "0R2J-2-GP"
			(at 0.064008 -3.993896 0)
			(unlocked yes)
			(layer "F.Fab")
			(hide yes)
			(effects
				(font
					(size 1.016 1.016)
					(thickness 0.1524)
				)
			)
		)
		(property "Device Type" "R402H16"
			(at 0.064008 -5.517896 0)
			(unlocked yes)
			(layer "F.Fab")
			(hide yes)
			(effects
				(font
					(size 1.016 1.016)
					(thickness 0.1524)
				)
			)
		)
		(duplicate_pad_numbers_are_jumpers no)
		(fp_line
			(start -0.508 -0.9398)
			(end -0.508 0.9398)
			(stroke
				(width 0.1524)
				(type default)
			)
			(layer "F.SilkS")
		)
		(fp_line
			(start 0.508 -0.9398)
			(end -0.508 -0.9398)
			(stroke
				(width 0.1524)
				(type default)
			)
			(layer "F.SilkS")
		)
		(fp_rect
			(start -0.508 0.9398)
			(end 0.508 -0.9398)
			(stroke
				(width 0)
				(type default)
			)
			(fill no)
			(layer "F.CrtYd")
		)
		(fp_rect
			(start -0.508 0.9398)
			(end 0.508 -0.9398)
			(stroke
				(width 0)
				(type default)
			)
			(fill no)
			(layer "F.Fab")
		)
		(pad "1" smd custom
			(at 0 -0.4445)
			(size 0.1397 0.1397)
			(layers "F.Cu" "F.Mask" "F.Paste")
			(net "PWM_OUT_FAN2_NET")
			(options
				(clearance outline)
				(anchor circle)
			)
			(primitives
				(gr_poly
					(pts
						(arc
							(start -0.1778 -0.2794)
							(mid -0.249642 -0.249642)
							(end -0.2794 -0.1778)
						)
						(arc
							(start -0.2794 0.1778)
							(mid -0.249642 0.249642)
							(end -0.1778 0.2794)
						)
						(arc
							(start 0.1778 0.2794)
							(mid 0.249642 0.249642)
							(end 0.2794 0.1778)
						)
						(arc
							(start 0.2794 -0.1778)
							(mid 0.249642 -0.249642)
							(end 0.1778 -0.2794)
						)
					)
					(width 0)
					(fill yes)
				)
			)
		)
		(pad "2" smd custom
			(at 0 0.4445)
			(size 0.1397 0.1397)
			(layers "F.Cu" "F.Mask" "F.Paste")
			(net "PWM_OUT_FAN2")
			(options
				(clearance outline)
				(anchor circle)
			)
			(primitives
				(gr_poly
					(pts
						(arc
							(start -0.1778 -0.2794)
							(mid -0.249642 -0.249642)
							(end -0.2794 -0.1778)
						)
						(arc
							(start -0.2794 0.1778)
							(mid -0.249642 0.249642)
							(end -0.1778 0.2794)
						)
						(arc
							(start 0.1778 0.2794)
							(mid 0.249642 0.249642)
							(end 0.2794 0.1778)
						)
						(arc
							(start 0.2794 -0.1778)
							(mid 0.249642 -0.249642)
							(end 0.1778 -0.2794)
						)
					)
					(width 0)
					(fill yes)
				)
			)
		)
	)
	(footprint ""
		(layer "F.Cu")
		(at 19.1262 -241.1984 90)
		(property "Reference" "PL7"
			(at 0 0 90)
			(layer "F.SilkS")
			(hide yes)
			(effects
				(font
					(size 1.27 1.27)
				)
			)
		)
		(property "Value" "IND-22UH-169-GP"
			(at -4.7498 0.5588 90)
			(unlocked yes)
			(layer "F.Fab")
			(hide yes)
			(effects
				(font
					(size 1.016 1.016)
					(thickness 0.1524)
				)
			)
		)
		(property "Device Type" "L6362-D620H119"
			(at -4.7498 -0.9652 90)
			(unlocked yes)
			(layer "F.Fab")
			(hide yes)
			(effects
				(font
					(size 1.016 1.016)
					(thickness 0.1524)
				)
			)
		)
		(duplicate_pad_numbers_are_jumpers no)
		(fp_line
			(start 1.667256 -3.8989)
			(end 3.3528 -2.213356)
			(stroke
				(width 0.1524)
				(type default)
			)
			(layer "F.SilkS")
		)
		(fp_line
			(start -1.667256 -3.8989)
			(end 1.667256 -3.8989)
			(stroke
				(width 0.1524)
				(type default)
			)
			(layer "F.SilkS")
		)
		(fp_line
			(start 3.3528 -2.213356)
			(end 3.3528 2.213356)
			(stroke
				(width 0.1524)
				(type default)
			)
			(layer "F.SilkS")
		)
		(fp_line
			(start -3.3528 -2.213356)
			(end -1.667256 -3.8989)
			(stroke
				(width 0.1524)
				(type default)
			)
			(layer "F.SilkS")
		)
		(fp_line
			(start 3.3528 2.213356)
			(end 1.667256 3.8989)
			(stroke
				(width 0.1524)
				(type default)
			)
			(layer "F.SilkS")
		)
		(fp_line
			(start -3.3528 2.213356)
			(end -3.3528 -2.213356)
			(stroke
				(width 0.1524)
				(type default)
			)
			(layer "F.SilkS")
		)
		(fp_line
			(start 1.667256 3.8989)
			(end -1.667256 3.8989)
			(stroke
				(width 0.1524)
				(type default)
			)
			(layer "F.SilkS")
		)
		(fp_line
			(start -1.667256 3.8989)
			(end -3.3528 2.213356)
			(stroke
				(width 0.1524)
				(type default)
			)
			(layer "F.SilkS")
		)
		(fp_poly
			(pts
				(xy 2.0574 3.1496) (xy -2.0574 3.1496) (xy -3.0988 2.1082) (xy -3.0988 -2.1082) (xy -2.0574 -3.1496)
				(xy 2.0574 -3.1496) (xy 3.0988 -2.1082) (xy 3.0988 2.1082)
			)
			(stroke
				(width 0)
				(type default)
			)
			(fill no)
			(layer "F.CrtYd")
		)
		(fp_poly
			(pts
				(xy 3.6068 2.318512) (xy 1.950212 3.9751) (xy -1.950212 3.9751) (xy -3.6068 2.318512) (xy -3.6068 -2.318512)
				(xy -1.950212 -3.9751) (xy 1.950212 -3.9751) (xy 3.6068 -2.318512) (xy 3.6068 -1.9177) (xy 3.0988 -1.9177)
				(xy 3.0988 -2.1082) (xy 2.0574 -3.1496) (xy -2.0574 -3.1496) (xy -3.0988 -2.1082) (xy -3.0988 2.1082)
				(xy -2.0574 3.1496) (xy 2.0574 3.1496) (xy 3.0988 2.1082) (xy 3.0988 -1.905) (xy 3.6068 -1.905)
			)
			(stroke
				(width 0)
				(type default)
			)
			(fill no)
			(layer "F.CrtYd")
		)
		(fp_poly
			(pts
				(xy -1.950212 3.9751) (xy -3.6068 2.318512) (xy -3.6068 -2.318512) (xy -1.950212 -3.9751) (xy 1.950212 -3.9751)
				(xy 3.6068 -2.318512) (xy 3.6068 2.318512) (xy 1.950212 3.9751)
			)
			(stroke
				(width 0)
				(type default)
			)
			(fill no)
			(layer "F.Fab")
		)
		(pad "1" smd rect
			(at 0 -2.895346 90)
			(size 2.2606 1.4986)
			(layers "F.Cu" "F.Mask" "F.Paste")
			(net "P3V3_LX")
		)
		(pad "2" smd rect
			(at 0 2.895346 90)
			(size 2.2606 1.4986)
			(layers "F.Cu" "F.Mask" "F.Paste")
			(net "P3V3_LX_COPPER")
		)
	)
	(footprint ""
		(layer "F.Cu")
		(at 11.811 -426.847 90)
		(property "Reference" "PD2"
			(at 0 0 90)
			(layer "F.SilkS")
			(hide yes)
			(effects
				(font
					(size 1.27 1.27)
				)
			)
		)
		(property "Value" "SMCJ15A-1-GP"
			(at -4.7244 1.5748 90)
			(unlocked yes)
			(layer "F.Fab")
			(hide yes)
			(effects
				(font
					(size 1.016 1.016)
					(thickness 0.1524)
				)
			)
		)
		(property "Device Type" "TVS794591-114297H104"
			(at -4.7244 0.0508 90)
			(unlocked yes)
			(layer "F.Fab")
			(hide yes)
			(effects
				(font
					(size 1.016 1.016)
					(thickness 0.1524)
				)
			)
		)
		(duplicate_pad_numbers_are_jumpers no)
		(fp_line
			(start 3.2004 -4.8641)
			(end -3.2004 -4.8641)
			(stroke
				(width 0.1524)
				(type default)
			)
			(layer "F.SilkS")
		)
		(fp_line
			(start -3.2004 -4.8641)
			(end -3.2004 4.8641)
			(stroke
				(width 0.1524)
				(type default)
			)
			(layer "F.SilkS")
		)
		(fp_line
			(start 3.2004 4.8641)
			(end 3.2004 -4.8641)
			(stroke
				(width 0.1524)
				(type default)
			)
			(layer "F.SilkS")
		)
		(fp_line
			(start -3.2004 4.8641)
			(end 3.2004 4.8641)
			(stroke
				(width 0.1524)
				(type default)
			)
			(layer "F.SilkS")
		)
		(fp_line
			(start 3.2004 5.0419)
			(end -3.2004 5.0419)
			(stroke
				(width 0.508)
				(type default)
			)
			(layer "F.SilkS")
		)
		(fp_rect
			(start -2.9464 3.9751)
			(end 2.9464 -3.9751)
			(stroke
				(width 0)
				(type default)
			)
			(fill no)
			(layer "F.CrtYd")
		)
		(fp_poly
			(pts
				(xy -3.4544 4.9403) (xy -3.4544 -4.9403) (xy 3.4544 -4.9403) (xy 3.4544 3.9624) (xy 2.9464 3.9624)
				(xy 2.9464 -3.9751) (xy -2.9464 -3.9751) (xy -2.9464 3.9751) (xy 3.4544 3.9751) (xy 3.4544 4.9403)
			)
			(stroke
				(width 0)
				(type default)
			)
			(fill no)
			(layer "F.CrtYd")
		)
		(fp_rect
			(start -3.4544 4.9403)
			(end 3.4544 -4.9403)
			(stroke
				(width 0)
				(type default)
			)
			(fill no)
			(layer "F.Fab")
		)
		(pad "A" smd rect
			(at 0 -3.591814 90)
			(size 3.2258 2.032)
			(layers "F.Cu" "F.Mask" "F.Paste")
			(net "GND")
		)
		(pad "K" smd rect
			(at 0 3.591814 90)
			(size 3.2258 2.032)
			(layers "F.Cu" "F.Mask" "F.Paste")
			(net "P12V_AUX")
		)
	)
	(footprint ""
		(layer "F.Cu")
		(at 6.1214 -174.7774 180)
		(property "Reference" "C53"
			(at 0 0 180)
			(layer "F.SilkS")
			(hide yes)
			(effects
				(font
					(size 1.27 1.27)
				)
			)
		)
		(property "Value" "SC1U16V3KX-5GP"
			(at 0 -2.8194 180)
			(unlocked yes)
			(layer "F.Fab")
			(hide yes)
			(effects
				(font
					(size 1.016 1.016)
					(thickness 0.1524)
				)
			)
		)
		(property "Device Type" "C603H36"
			(at 0 -4.3434 180)
			(unlocked yes)
			(layer "F.Fab")
			(hide yes)
			(effects
				(font
					(size 1.016 1.016)
					(thickness 0.1524)
				)
			)
		)
		(duplicate_pad_numbers_are_jumpers no)
		(fp_line
			(start 0.508 0)
			(end -0.508 0)
			(stroke
				(width 0.2032)
				(type default)
			)
			(layer "F.SilkS")
		)
		(fp_rect
			(start -0.5842 1.3335)
			(end 0.5842 -1.3335)
			(stroke
				(width 0)
				(type default)
			)
			(fill no)
			(layer "F.CrtYd")
		)
		(fp_rect
			(start -0.5842 1.3335)
			(end 0.5842 -1.3335)
			(stroke
				(width 0)
				(type default)
			)
			(fill no)
			(layer "F.Fab")
		)
		(pad "1" smd custom
			(at 0 -0.762 180)
			(size 0.2159 0.2159)
			(layers "F.Cu" "F.Mask" "F.Paste")
			(net "P3V3")
			(options
				(clearance outline)
				(anchor circle)
			)
			(primitives
				(gr_poly
					(pts
						(arc
							(start -0.3302 -0.4318)
							(mid -0.402042 -0.402042)
							(end -0.4318 -0.3302)
						)
						(arc
							(start -0.4318 0.3302)
							(mid -0.402042 0.402042)
							(end -0.3302 0.4318)
						)
						(arc
							(start 0.3302 0.4318)
							(mid 0.402042 0.402042)
							(end 0.4318 0.3302)
						)
						(arc
							(start 0.4318 -0.3302)
							(mid 0.402042 -0.402042)
							(end 0.3302 -0.4318)
						)
					)
					(width 0)
					(fill yes)
				)
			)
		)
		(pad "2" smd custom
			(at 0 0.762 180)
			(size 0.2159 0.2159)
			(layers "F.Cu" "F.Mask" "F.Paste")
			(net "GND")
			(options
				(clearance outline)
				(anchor circle)
			)
			(primitives
				(gr_poly
					(pts
						(arc
							(start -0.3302 -0.4318)
							(mid -0.402042 -0.402042)
							(end -0.4318 -0.3302)
						)
						(arc
							(start -0.4318 0.3302)
							(mid -0.402042 0.402042)
							(end -0.3302 0.4318)
						)
						(arc
							(start 0.3302 0.4318)
							(mid 0.402042 0.402042)
							(end 0.4318 0.3302)
						)
						(arc
							(start 0.4318 -0.3302)
							(mid 0.402042 -0.402042)
							(end 0.3302 -0.4318)
						)
					)
					(width 0)
					(fill yes)
				)
			)
		)
	)
	(footprint ""
		(layer "F.Cu")
		(at 14.8844 -39.4462 90)
		(property "Reference" "R120"
			(at 0 0 90)
			(layer "F.SilkS")
			(hide yes)
			(effects
				(font
					(size 1.27 1.27)
				)
			)
		)
		(property "Value" "470R2F-GP"
			(at 0.064008 -3.993896 90)
			(unlocked yes)
			(layer "F.Fab")
			(hide yes)
			(effects
				(font
					(size 1.016 1.016)
					(thickness 0.1524)
				)
			)
		)
		(property "Device Type" "R402H16"
			(at 0.064008 -5.517896 90)
			(unlocked yes)
			(layer "F.Fab")
			(hide yes)
			(effects
				(font
					(size 1.016 1.016)
					(thickness 0.1524)
				)
			)
		)
		(duplicate_pad_numbers_are_jumpers no)
		(fp_line
			(start 0.508 -0.9398)
			(end -0.508 -0.9398)
			(stroke
				(width 0.1524)
				(type default)
			)
			(layer "F.SilkS")
		)
		(fp_line
			(start -0.508 -0.9398)
			(end -0.508 0.9398)
			(stroke
				(width 0.1524)
				(type default)
			)
			(layer "F.SilkS")
		)
		(fp_rect
			(start -0.508 0.9398)
			(end 0.508 -0.9398)
			(stroke
				(width 0)
				(type default)
			)
			(fill no)
			(layer "F.CrtYd")
		)
		(fp_rect
			(start -0.508 0.9398)
			(end 0.508 -0.9398)
			(stroke
				(width 0)
				(type default)
			)
			(fill no)
			(layer "F.Fab")
		)
		(pad "1" smd custom
			(at 0 -0.4445 90)
			(size 0.1397 0.1397)
			(layers "F.Cu" "F.Mask" "F.Paste")
			(net "SEB_PEER_2B_HB")
			(options
				(clearance outline)
				(anchor circle)
			)
			(primitives
				(gr_poly
					(pts
						(arc
							(start -0.1778 -0.2794)
							(mid -0.249642 -0.249642)
							(end -0.2794 -0.1778)
						)
						(arc
							(start -0.2794 0.1778)
							(mid -0.249642 0.249642)
							(end -0.1778 0.2794)
						)
						(arc
							(start 0.1778 0.2794)
							(mid 0.249642 0.249642)
							(end 0.2794 0.1778)
						)
						(arc
							(start 0.2794 -0.1778)
							(mid 0.249642 -0.249642)
							(end 0.1778 -0.2794)
						)
					)
					(width 0)
					(fill yes)
				)
			)
		)
		(pad "2" smd custom
			(at 0 0.4445 90)
			(size 0.1397 0.1397)
			(layers "F.Cu" "F.Mask" "F.Paste")
			(net "GND")
			(options
				(clearance outline)
				(anchor circle)
			)
			(primitives
				(gr_poly
					(pts
						(arc
							(start -0.1778 -0.2794)
							(mid -0.249642 -0.249642)
							(end -0.2794 -0.1778)
						)
						(arc
							(start -0.2794 0.1778)
							(mid -0.249642 0.249642)
							(end -0.1778 0.2794)
						)
						(arc
							(start 0.1778 0.2794)
							(mid 0.249642 0.249642)
							(end 0.2794 0.1778)
						)
						(arc
							(start 0.2794 -0.1778)
							(mid 0.249642 -0.249642)
							(end 0.1778 -0.2794)
						)
					)
					(width 0)
					(fill yes)
				)
			)
		)
	)
	(footprint ""
		(layer "F.Cu")
		(at 37.032692 -289.281362 180)
		(property "Reference" "TC17"
			(at 0 0 180)
			(layer "F.SilkS")
			(hide yes)
			(effects
				(font
					(size 1.27 1.27)
				)
			)
		)
		(property "Value" "ST15U25VDM-1-GP"
			(at 0 -9.6012 180)
			(unlocked yes)
			(layer "F.Fab")
			(hide yes)
			(effects
				(font
					(size 1.016 1.016)
					(thickness 0.1524)
				)
			)
		)
		(property "Device Type" "CT7343H79"
			(at 0 -11.1252 180)
			(unlocked yes)
			(layer "F.Fab")
			(hide yes)
			(effects
				(font
					(size 1.016 1.016)
					(thickness 0.1524)
				)
			)
		)
		(duplicate_pad_numbers_are_jumpers no)
		(fp_line
			(start 2.286 4.8768)
			(end -2.286 4.8768)
			(stroke
				(width 0.1524)
				(type default)
			)
			(layer "F.SilkS")
		)
		(fp_line
			(start 2.286 2.032)
			(end 2.286 4.8768)
			(stroke
				(width 0.1524)
				(type default)
			)
			(layer "F.SilkS")
		)
		(fp_line
			(start 2.286 -2.032)
			(end 2.286 -4.8768)
			(stroke
				(width 0.1524)
				(type default)
			)
			(layer "F.SilkS")
		)
		(fp_line
			(start 2.286 -4.8768)
			(end -2.286 -4.8768)
			(stroke
				(width 0.1524)
				(type default)
			)
			(layer "F.SilkS")
		)
		(fp_line
			(start 2.1082 -4.699)
			(end -2.1082 -4.699)
			(stroke
				(width 0.508)
				(type default)
			)
			(layer "F.SilkS")
		)
		(fp_line
			(start -2.286 4.8768)
			(end -2.286 2.032)
			(stroke
				(width 0.1524)
				(type default)
			)
			(layer "F.SilkS")
		)
		(fp_line
			(start -2.286 -4.8768)
			(end -2.286 -2.032)
			(stroke
				(width 0.1524)
				(type default)
			)
			(layer "F.SilkS")
		)
		(fp_rect
			(start -2.1463 3.6449)
			(end 2.1463 -3.6449)
			(stroke
				(width 0)
				(type default)
			)
			(fill no)
			(layer "F.CrtYd")
		)
		(fp_poly
			(pts
				(xy -2.54 4.953) (xy -2.54 4.2926) (xy -3.81 4.2926) (xy -3.81 -4.2926) (xy -2.54 -4.2926) (xy -2.54 -4.953)
				(xy 2.54 -4.953) (xy 2.54 -4.2926) (xy 3.81 -4.2926) (xy 3.81 -1.6256) (xy 2.1463 -1.6256) (xy 2.1463 -3.6449)
				(xy -2.1463 -3.6449) (xy -2.1463 3.6449) (xy 2.1463 3.6449) (xy 2.1463 -1.6129) (xy 3.81 -1.6129)
				(xy 3.81 4.2926) (xy 2.54 4.2926) (xy 2.54 4.953)
			)
			(stroke
				(width 0)
				(type default)
			)
			(fill no)
			(layer "F.CrtYd")
		)
		(fp_rect
			(start 2.54 4.2926)
			(end 3.81 -4.2926)
			(stroke
				(width 0)
				(type default)
			)
			(fill no)
			(layer "F.Fab")
		)
		(fp_rect
			(start -2.54 4.953)
			(end 2.54 -4.953)
			(stroke
				(width 0)
				(type default)
			)
			(fill no)
			(layer "F.Fab")
		)
		(fp_rect
			(start -3.81 4.2926)
			(end -2.54 -4.2926)
			(stroke
				(width 0)
				(type default)
			)
			(fill no)
			(layer "F.Fab")
		)
		(pad "1" smd rect
			(at 0 -3.1496 180)
			(size 2.413 2.286)
			(layers "F.Cu" "F.Mask" "F.Paste")
			(net "P12V")
		)
		(pad "2" smd rect
			(at 0 3.1496 180)
			(size 2.413 2.286)
			(layers "F.Cu" "F.Mask" "F.Paste")
			(net "GND")
		)
		(zone
			(layer "F.Cu")
			(hatch none 0.5)
			(connect_pads
				(clearance 0)
			)
			(min_thickness 0.25)
			(keepout
				(tracks allowed)
				(vias not_allowed)
				(pads allowed)
				(copperpour not_allowed)
				(footprints allowed)
			)
			(placement
				(enabled no)
				(sheetname "")
			)
			(fill
				(thermal_gap 0.5)
				(thermal_bridge_width 0.5)
				(island_removal_mode 0)
			)
			(polygon
				(pts
					(xy 35.521392 -287.592262) (xy 35.521392 -284.683962) (xy 38.543992 -284.683962) (xy 38.543992 -287.579562)
					(xy 38.543992 -287.909762) (xy 35.521392 -287.909762)
				)
			)
		)
		(zone
			(layer "F.Cu")
			(hatch none 0.5)
			(connect_pads
				(clearance 0)
			)
			(min_thickness 0.25)
			(keepout
				(tracks allowed)
				(vias not_allowed)
				(pads allowed)
				(copperpour not_allowed)
				(footprints allowed)
			)
			(placement
				(enabled no)
				(sheetname "")
			)
			(fill
				(thermal_gap 0.5)
				(thermal_bridge_width 0.5)
				(island_removal_mode 0)
			)
			(polygon
				(pts
					(xy 38.543992 -293.878762) (xy 35.521392 -293.878762) (xy 35.521392 -290.983162) (xy 35.521392 -290.652962)
					(xy 38.543992 -290.652962) (xy 38.543992 -290.983162)
				)
			)
		)
	)
)
